# BASEBOARD_FAB2 (Tioga Pass) — schematic netlist excerpt (pin names and nets, part order shuffled) for the footprints in the layout excerpt that follows; sources: Cadence DE-HDL packaged netlist, KiCad conversion of Wiwynn_Tioga_Pass_MB.brd

C2L26  CAP_A  0.01UF 25V 10% X7R  pkg 0402V  page 173 : A = SATA6G_P5_TX_C_DN ; B = SATA6G_PCH_PCIE_UP_SATA_TXN<5>
R8D40  RES  20.0K 1% CHIP  pkg 0402  page 196 : A = A_PG_P12V_MAIN ; B = GND
C6P15  CAP  10UF 16V 10% X6S  pkg 0805  page 203 : A = VR_FET_SW_P12V_STBY_PVCCIN_CPU0 ; B = GND

(kicad_pcb
	(version 20260206)
	(generator "pcbnew")
	(generator_version "10.0")
	(general
		(thickness 1.6)
		(legacy_teardrops no)
	)
	(paper "A4")
	(title_block
		(title "Wiwynn_Tioga_Pass_MB.brd")
		(comment 1 "Tioga Pass / footprints 4179-4181 of 4770")
	)
	(layers
		(0 "F.Cu" signal "TOP")
		(4 "In1.Cu" signal "L2GND")
		(6 "In2.Cu" signal "L3")
		(8 "In3.Cu" signal "L4GND")
		(10 "In4.Cu" signal "L5")
		(12 "In5.Cu" signal "L6GND")
		(14 "In6.Cu" signal "L7VCC")
		(16 "In7.Cu" signal "L8VCC")
		(18 "In8.Cu" signal "L9GND")
		(20 "In9.Cu" signal "L10")
		(22 "In10.Cu" signal "L11GND")
		(24 "In11.Cu" signal "L12")
		(26 "In12.Cu" signal "L13GND")
		(2 "B.Cu" signal "BOTTOM")
		(9 "F.Adhes" user "F.Adhesive")
		(11 "B.Adhes" user "B.Adhesive")
		(13 "F.Paste" user "Package Geometry/Pastemask Top")
		(15 "B.Paste" user "Package Geometry/Pastemask Bottom")
		(5 "F.SilkS" user "Ref Des/Silkscreen Top")
		(7 "B.SilkS" user "Ref Des/Silkscreen Bottom")
		(1 "F.Mask" user "Board Geometry/Soldermask Top")
		(3 "B.Mask" user "Board Geometry/Soldermask Bottom")
		(17 "Dwgs.User" user "User.Drawings")
		(19 "Cmts.User" user "User.Comments")
		(21 "Eco1.User" user "User.Eco1")
		(23 "Eco2.User" user "User.Eco2")
		(25 "Edge.Cuts" user "Board Geometry/Outline")
		(27 "Margin" user)
		(31 "F.CrtYd" user "Package Geometry/Place Bound Top")
		(29 "B.CrtYd" user "Package Geometry/Place Bound Bottom")
		(35 "F.Fab" user "Ref Des/Assembly Top")
		(33 "B.Fab" user "Ref Des/Assembly Bottom")
	)
	(footprint ""
		(layer "B.Cu")
		(at 407.9113 -8.763 90)
		(property "Reference" "R8D40"
			(at 0 0 90)
			(layer "B.SilkS")
			(hide yes)
			(effects
				(font
					(size 1.27 1.27)
				)
				(justify mirror)
			)
		)
		(property "Value" ""
			(at 0 0 90)
			(layer "B.Fab")
			(effects
				(font
					(size 1.27 1.27)
				)
				(justify mirror)
			)
		)
		(duplicate_pad_numbers_are_jumpers no)
		(fp_poly
			(pts
				(xy 0.2794 -0.1016) (xy -0.2794 -0.1016) (xy -0.2794 0.9906) (xy 0.2794 0.9906)
			)
			(stroke
				(width 0)
				(type default)
			)
			(fill no)
			(layer "B.CrtYd")
		)
		(fp_line
			(start 0.2794 -0.1016)
			(end 0.2794 0.9906)
			(stroke
				(width 0.1)
				(type default)
			)
			(layer "B.Fab")
		)
		(fp_line
			(start -0.2794 -0.1016)
			(end 0.2794 -0.1016)
			(stroke
				(width 0.1)
				(type default)
			)
			(layer "B.Fab")
		)
		(fp_line
			(start 0.2794 0.9906)
			(end -0.2794 0.9906)
			(stroke
				(width 0.1)
				(type default)
			)
			(layer "B.Fab")
		)
		(fp_line
			(start -0.2794 0.9906)
			(end -0.2794 -0.1016)
			(stroke
				(width 0.1)
				(type default)
			)
			(layer "B.Fab")
		)
		(pad "1" smd rect
			(at 0 0 270)
			(size 0.508 0.508)
			(layers "B.Cu" "B.Mask" "B.Paste")
			(net "A_PG_P12V_MAIN")
		)
		(pad "2" smd rect
			(at 0 0.889 270)
			(size 0.508 0.508)
			(layers "B.Cu" "B.Mask" "B.Paste")
			(net "GND")
		)
		(zone
			(layer "B.Cu")
			(hatch none 0.5)
			(connect_pads
				(clearance 0)
			)
			(min_thickness 0.25)
			(keepout
				(tracks allowed)
				(vias not_allowed)
				(pads allowed)
				(copperpour not_allowed)
				(footprints allowed)
			)
			(placement
				(enabled no)
				(sheetname "")
			)
			(fill
				(thermal_gap 0.5)
				(thermal_bridge_width 0.5)
				(island_removal_mode 0)
			)
			(polygon
				(pts
					(xy 408.1653 -9.017) (xy 408.1653 -8.509) (xy 408.5463 -8.509) (xy 408.5463 -9.017)
				)
			)
		)
		(zone
			(layer "B.Cu")
			(hatch none 0.5)
			(connect_pads
				(clearance 0)
			)
			(min_thickness 0.25)
			(keepout
				(tracks not_allowed)
				(vias allowed)
				(pads allowed)
				(copperpour not_allowed)
				(footprints allowed)
			)
			(placement
				(enabled no)
				(sheetname "")
			)
			(fill
				(thermal_gap 0.5)
				(thermal_bridge_width 0.5)
				(island_removal_mode 0)
			)
			(polygon
				(pts
					(xy 408.5463 -9.017) (xy 408.5463 -8.509) (xy 408.1653 -8.509) (xy 408.1653 -9.017)
				)
			)
		)
	)
	(footprint ""
		(layer "B.Cu")
		(at 411.861 -146.431 -90)
		(property "Reference" "C2L26"
			(at 0 0 90)
			(layer "B.SilkS")
			(hide yes)
			(effects
				(font
					(size 1.27 1.27)
				)
				(justify mirror)
			)
		)
		(property "Value" ""
			(at 0 0 90)
			(layer "B.Fab")
			(effects
				(font
					(size 1.27 1.27)
				)
				(justify mirror)
			)
		)
		(duplicate_pad_numbers_are_jumpers no)
		(fp_poly
			(pts
				(xy -0.3048 -0.1016) (xy -0.3048 0.9906) (xy 0.3048 0.9906) (xy 0.3048 -0.1016)
			)
			(stroke
				(width 0)
				(type default)
			)
			(fill no)
			(layer "B.CrtYd")
		)
		(fp_line
			(start -0.3048 0.9906)
			(end -0.3048 -0.1016)
			(stroke
				(width 0.1)
				(type default)
			)
			(layer "B.Fab")
		)
		(fp_line
			(start 0.3048 0.9906)
			(end -0.3048 0.9906)
			(stroke
				(width 0.1)
				(type default)
			)
			(layer "B.Fab")
		)
		(fp_line
			(start -0.3048 -0.1016)
			(end 0.3048 -0.1016)
			(stroke
				(width 0.1)
				(type default)
			)
			(layer "B.Fab")
		)
		(fp_line
			(start 0.3048 -0.1016)
			(end 0.3048 0.9906)
			(stroke
				(width 0.1)
				(type default)
			)
			(layer "B.Fab")
		)
		(pad "1" smd rect
			(at 0 0 90)
			(size 0.508 0.508)
			(layers "B.Cu" "B.Mask" "B.Paste")
			(net "SATA6G_P5_TX_C_DN")
		)
		(pad "2" smd rect
			(at 0 0.889 90)
			(size 0.508 0.508)
			(layers "B.Cu" "B.Mask" "B.Paste")
			(net "SATA6G_PCH_PCIE_UP_SATA_TXN<5>")
		)
		(zone
			(layer "B.Cu")
			(hatch none 0.5)
			(connect_pads
				(clearance 0)
			)
			(min_thickness 0.25)
			(keepout
				(tracks not_allowed)
				(vias allowed)
				(pads allowed)
				(copperpour not_allowed)
				(footprints allowed)
			)
			(placement
				(enabled no)
				(sheetname "")
			)
			(fill
				(thermal_gap 0.5)
				(thermal_bridge_width 0.5)
				(island_removal_mode 0)
			)
			(polygon
				(pts
					(xy 411.226 -146.177) (xy 411.226 -146.685) (xy 411.607 -146.685) (xy 411.607 -146.177)
				)
			)
		)
		(zone
			(layer "B.Cu")
			(hatch none 0.5)
			(connect_pads
				(clearance 0)
			)
			(min_thickness 0.25)
			(keepout
				(tracks allowed)
				(vias not_allowed)
				(pads allowed)
				(copperpour not_allowed)
				(footprints allowed)
			)
			(placement
				(enabled no)
				(sheetname "")
			)
			(fill
				(thermal_gap 0.5)
				(thermal_bridge_width 0.5)
				(island_removal_mode 0)
			)
			(polygon
				(pts
					(xy 411.607 -146.177) (xy 411.607 -146.685) (xy 411.226 -146.685) (xy 411.226 -146.177)
				)
			)
		)
	)
	(footprint ""
		(layer "B.Cu")
		(at 197.848728 -81.191862 90)
		(property "Reference" "C6P15"
			(at 0 0 90)
			(layer "B.SilkS")
			(hide yes)
			(effects
				(font
					(size 1.27 1.27)
				)
				(justify mirror)
			)
		)
		(property "Value" ""
			(at 0 0 90)
			(layer "B.Fab")
			(effects
				(font
					(size 1.27 1.27)
				)
				(justify mirror)
			)
		)
		(duplicate_pad_numbers_are_jumpers no)
		(fp_rect
			(start -0.7239 -0.2159)
			(end 0.7239 1.9939)
			(stroke
				(width 0)
				(type default)
			)
			(fill no)
			(layer "B.CrtYd")
		)
		(fp_line
			(start 0.7239 -0.2159)
			(end 0.7239 1.9939)
			(stroke
				(width 0.1)
				(type default)
			)
			(layer "B.Fab")
		)
		(fp_line
			(start -0.7239 -0.2159)
			(end 0.7239 -0.2159)
			(stroke
				(width 0.1)
				(type default)
			)
			(layer "B.Fab")
		)
		(fp_line
			(start 0.7239 1.9939)
			(end -0.7239 1.9939)
			(stroke
				(width 0.1)
				(type default)
			)
			(layer "B.Fab")
		)
		(fp_line
			(start -0.7239 1.9939)
			(end -0.7239 -0.2159)
			(stroke
				(width 0.1)
				(type default)
			)
			(layer "B.Fab")
		)
		(pad "1" smd rect
			(at 0 0 270)
			(size 1.27 1.016)
			(layers "B.Cu" "B.Mask" "B.Paste")
			(net "VR_FET_SW_P12V_STBY_PVCCIN_CPU0")
		)
		(pad "2" smd rect
			(at 0 1.778 270)
			(size 1.27 1.016)
			(layers "B.Cu" "B.Mask" "B.Paste")
			(net "GND")
		)
		(zone
			(layer "B.Cu")
			(hatch none 0.5)
			(connect_pads
				(clearance 0)
			)
			(min_thickness 0.25)
			(keepout
				(tracks not_allowed)
				(vias allowed)
				(pads allowed)
				(copperpour not_allowed)
				(footprints allowed)
			)
			(placement
				(enabled no)
				(sheetname "")
			)
			(fill
				(thermal_gap 0.5)
				(thermal_bridge_width 0.5)
				(island_removal_mode 0)
			)
			(polygon
				(pts
					(xy 198.356728 -80.556862) (xy 199.118728 -80.556862) (xy 199.118728 -81.826862) (xy 198.356728 -81.826862)
				)
			)
		)
	)
)
